(kicad_pcb
	(version 20241229)
	(generator "pcbnew")
	(generator_version "9.0")
	(general
		(thickness 1.6296)
		(legacy_teardrops no)
	)
	(paper "A3")
	(title_block
		(title "Thunderbolt to 10GbE adapter")
		(date "2026-04-21")
		(rev "1.1.0")
		(company "Antmicro Ltd")
		(comment 1 "www.antmicro.com")
		(comment 9 "footprints 159-163 of 703")
	)
	(layers
		(0 "F.Cu" signal)
		(4 "In1.Cu" signal)
		(6 "In2.Cu" signal)
		(8 "In3.Cu" signal)
		(10 "In4.Cu" signal)
		(12 "In5.Cu" signal)
		(14 "In6.Cu" signal)
		(2 "B.Cu" signal)
		(9 "F.Adhes" user "F.Adhesive")
		(11 "B.Adhes" user "B.Adhesive")
		(13 "F.Paste" user)
		(15 "B.Paste" user)
		(5 "F.SilkS" user "F.Silkscreen")
		(7 "B.SilkS" user "B.Silkscreen")
		(1 "F.Mask" user)
		(3 "B.Mask" user)
		(17 "Dwgs.User" user "User.Drawings")
		(19 "Cmts.User" user "User.Comments")
		(21 "Eco1.User" user "User.Eco1")
		(23 "Eco2.User" user "User.Eco2")
		(25 "Edge.Cuts" user)
		(27 "Margin" user)
		(31 "F.CrtYd" user "F.Courtyard")
		(29 "B.CrtYd" user "B.Courtyard")
		(35 "F.Fab" user)
		(33 "B.Fab" user)
	)
	(footprint "antmicro-footprints:R_0402_1005Metric"
		(layer "F.Cu")
		(at 160.105 67.125 -90)
		(descr "Resistor SMD 0402")
		(tags "resistor SMD 0402")
		(property "Reference" "R189"
			(at -12.324999 -20.295 270)
			(layer "F.SilkS")
			(effects
				(font
					(size 0.7 0.7)
					(thickness 0.15)
				)
			)
		)
		(property "Value" "R_22R_0402"
			(at -1.011843 1.772047 270)
			(layer "F.Fab")
			(effects
				(font
					(size 0.7 0.7)
					(thickness 0.15)
				)
				(justify left bottom)
			)
		)
		(property "Datasheet" "https://www.bourns.com/docs/product-datasheets/cr.pdf"
			(at 0 0 270)
			(layer "F.Fab")
			(hide yes)
			(effects
				(font
					(size 1.27 1.27)
					(thickness 0.15)
				)
			)
		)
		(property "Description" "SMD Chip Resistor, 22 ohm, ± 1%, 62.5 mW, 0402 [1005 Metric], Thick Film, General Purpose"
			(at 0 0 270)
			(layer "F.Fab")
			(hide yes)
			(effects
				(font
					(size 1.27 1.27)
					(thickness 0.15)
				)
			)
		)
		(property "MPN" "CR0402-FX-22R0GLF"
			(at 0 0 270)
			(unlocked yes)
			(layer "F.Fab")
			(hide yes)
			(effects
				(font
					(size 1 1)
					(thickness 0.15)
				)
			)
		)
		(property "Manufacturer" "Bourns"
			(at 0 0 270)
			(unlocked yes)
			(layer "F.Fab")
			(hide yes)
			(effects
				(font
					(size 1 1)
					(thickness 0.15)
				)
			)
		)
		(property "License" "Apache-2.0"
			(at 0 0 270)
			(unlocked yes)
			(layer "F.Fab")
			(hide yes)
			(effects
				(font
					(size 1 1)
					(thickness 0.15)
				)
			)
		)
		(property "Author" "Antmicro"
			(at 0 0 270)
			(unlocked yes)
			(layer "F.Fab")
			(hide yes)
			(effects
				(font
					(size 1 1)
					(thickness 0.15)
				)
			)
		)
		(property "Val" "22R"
			(at 0 0 270)
			(unlocked yes)
			(layer "F.Fab")
			(hide yes)
			(effects
				(font
					(size 1 1)
					(thickness 0.15)
				)
			)
		)
		(property "Tolerance" "1%"
			(at 0 0 270)
			(unlocked yes)
			(layer "F.Fab")
			(hide yes)
			(effects
				(font
					(size 1 1)
					(thickness 0.15)
				)
			)
		)
		(sheetname "/X710-AT2 10GbE/")
		(sheetfile "x710-at2-10gbe.kicad_sch")
		(attr smd)
		(fp_rect
			(start -0.925 -0.47)
			(end 0.925 0.47)
			(stroke
				(width 0.05)
				(type default)
			)
			(fill no)
			(layer "F.CrtYd")
		)
		(fp_rect
			(start -0.5 -0.25)
			(end 0.5 0.25)
			(stroke
				(width 0.15)
				(type solid)
			)
			(fill no)
			(layer "F.Fab")
		)
		(fp_text user "${REFERENCE}"
			(at -0.95 3.168 270)
			(layer "F.Fab")
			(effects
				(font
					(size 0.7 0.7)
					(thickness 0.15)
				)
				(justify left bottom)
			)
		)
		(fp_text user "License: Apache-2.0"
			(at -0.95 5.169 270)
			(layer "F.Fab")
			(effects
				(font
					(size 0.7 0.7)
					(thickness 0.15)
				)
				(justify left bottom)
			)
		)
		(fp_text user "Author: Antmicro"
			(at -0.95 4.169 270)
			(layer "F.Fab")
			(effects
				(font
					(size 0.7 0.7)
					(thickness 0.15)
				)
				(justify left bottom)
			)
		)
		(pad "1" smd roundrect
			(at -0.48 0 270)
			(size 0.59 0.64)
			(layers "F.Cu" "F.Mask" "F.Paste")
			(roundrect_rratio 0.25)
			(net 114 "/X710-AT2 10GbE/25MHZ_OSC_R.-")
			(pintype "passive")
		)
		(pad "2" smd roundrect
			(at 0.48 0 270)
			(size 0.59 0.64)
			(layers "F.Cu" "F.Mask" "F.Paste")
			(roundrect_rratio 0.25)
			(net 55 "/X710-AT2 10GbE/25MHZ_OSC_AC.-")
			(pintype "passive")
		)
	)
	(footprint "antmicro-footprints:Resonator_SMD_Abracon_ABM8G_3.2x2.5mm"
		(layer "F.Cu")
		(at 117.5 130.25 180)
		(property "Reference" "Y2"
			(at -2.1 -0.95 0)
			(layer "F.SilkS")
			(effects
				(font
					(size 0.7 0.7)
					(thickness 0.15)
				)
				(justify left bottom)
			)
		)
		(property "Value" "Resonator_25MHz_ABM8G"
			(at -1.75 2.548 180)
			(layer "F.Fab")
			(effects
				(font
					(size 0.7 0.7)
					(thickness 0.15)
				)
				(justify left bottom)
			)
		)
		(property "Datasheet" "https://abracon.com/Resonators/ABM8G.pdf"
			(at 0 0 180)
			(layer "F.Fab")
			(hide yes)
			(effects
				(font
					(size 1.27 1.27)
					(thickness 0.15)
				)
			)
		)
		(property "Description" "Crystal, 25 MHz, SMD, 3.2mm x 2.5mm, 30 ppm, 18 pF, 20 ppm, ABM8G"
			(at 0 0 180)
			(layer "F.Fab")
			(hide yes)
			(effects
				(font
					(size 1.27 1.27)
					(thickness 0.15)
				)
			)
		)
		(property "MPN" "ABM8G-25.000MHZ-18-D2Y-T3"
			(at 0 0 180)
			(unlocked yes)
			(layer "F.Fab")
			(hide yes)
			(effects
				(font
					(size 1 1)
					(thickness 0.15)
				)
			)
		)
		(property "Manufacturer" "Abracon"
			(at 0 0 180)
			(unlocked yes)
			(layer "F.Fab")
			(hide yes)
			(effects
				(font
					(size 1 1)
					(thickness 0.15)
				)
			)
		)
		(property "License" "Apache-2.0"
			(at 0 0 180)
			(unlocked yes)
			(layer "F.Fab")
			(hide yes)
			(effects
				(font
					(size 1 1)
					(thickness 0.15)
				)
			)
		)
		(property "Author" "Antmicro"
			(at 0 0 180)
			(unlocked yes)
			(layer "F.Fab")
			(hide yes)
			(effects
				(font
					(size 1 1)
					(thickness 0.15)
				)
			)
		)
		(property "Val" "25 MHz"
			(at 0 0 180)
			(unlocked yes)
			(layer "F.Fab")
			(hide yes)
			(effects
				(font
					(size 1 1)
					(thickness 0.15)
				)
			)
		)
		(sheetname "/TB Controller/")
		(sheetfile "tb.kicad_sch")
		(attr smd)
		(fp_line
			(start 1.6 0.3)
			(end 1.6 -0.2)
			(stroke
				(width 0.15)
				(type solid)
			)
			(layer "F.SilkS")
		)
		(fp_line
			(start -0.35 1.25)
			(end 0.45 1.25)
			(stroke
				(width 0.15)
				(type solid)
			)
			(layer "F.SilkS")
		)
		(fp_line
			(start -0.35 -1.25)
			(end 0.45 -1.25)
			(stroke
				(width 0.15)
				(type solid)
			)
			(layer "F.SilkS")
		)
		(fp_line
			(start -1.6 0.3)
			(end -1.6 -0.2)
			(stroke
				(width 0.15)
				(type solid)
			)
			(layer "F.SilkS")
		)
		(fp_circle
			(center -1.75 1.5)
			(end -1.7 1.5)
			(stroke
				(width 0.15)
				(type solid)
			)
			(fill no)
			(layer "F.SilkS")
		)
		(fp_rect
			(start -1.907 -1.55)
			(end 2.006 1.649)
			(stroke
				(width 0.05)
				(type solid)
			)
			(fill no)
			(layer "F.CrtYd")
		)
		(fp_text user "Author: Antmicro"
			(at -1.75 5 180)
			(layer "F.Fab")
			(effects
				(font
					(size 0.7 0.7)
					(thickness 0.15)
				)
				(justify left bottom)
			)
		)
		(fp_text user "${REFERENCE}"
			(at -1.75 3.75 180)
			(layer "F.Fab")
			(effects
				(font
					(size 0.7 0.7)
					(thickness 0.15)
				)
				(justify left bottom)
			)
		)
		(fp_text user "License: Apache-2.0"
			(at -1.75 6.5 180)
			(layer "F.Fab")
			(effects
				(font
					(size 0.7 0.7)
					(thickness 0.15)
				)
				(justify left bottom)
			)
		)
		(pad "1" smd roundrect
			(at -1.101 0.949 180)
			(size 1.3 1.1)
			(layers "F.Cu" "F.Mask" "F.Paste")
			(roundrect_rratio 0)
			(chamfer_ratio 0.2)
			(chamfer bottom_left)
			(net 331 "/TB Controller/XTAL_25_OUT")
			(pintype "passive")
		)
		(pad "2" smd rect
			(at 1.199 0.949 180)
			(size 1.3 1.1)
			(layers "F.Cu" "F.Mask" "F.Paste")
			(net 23 "GND")
			(pinfunction "SH")
			(pintype "passive")
		)
		(pad "3" smd rect
			(at 1.199 -0.85 180)
			(size 1.3 1.1)
			(layers "F.Cu" "F.Mask" "F.Paste")
			(net 330 "/TB Controller/XTAL_25_IN")
			(pintype "passive")
		)
		(pad "4" smd rect
			(at -1.101 -0.85 180)
			(size 1.3 1.1)
			(layers "F.Cu" "F.Mask" "F.Paste")
			(net 23 "GND")
			(pinfunction "SH")
			(pintype "passive")
		)
	)
	(footprint "antmicro-footprints:C_0603_1608Metric_EIA"
		(layer "F.Cu")
		(at 162.555 99.224999 -90)
		(descr "Capacitor SMD 0603, IPC-7351 Density Level A")
		(tags "Capacitor 0603")
		(property "Reference" "C155"
			(at 0 -7.695 270)
			(layer "F.SilkS")
			(effects
				(font
					(size 0.7 0.7)
					(thickness 0.15)
				)
			)
		)
		(property "Value" "C_22u_16V_0603"
			(at -1.42757 1.770288 270)
			(layer "F.Fab")
			(effects
				(font
					(size 0.7 0.7)
					(thickness 0.15)
				)
				(justify left bottom)
			)
		)
		(property "Datasheet" "https://product.samsungsem.com/mlcc/CL10A226MO7JZN.do"
			(at 0 0 270)
			(layer "F.Fab")
			(hide yes)
			(effects
				(font
					(size 1.27 1.27)
					(thickness 0.15)
				)
			)
		)
		(property "Description" "SMD Multilayer Ceramic Capacitor"
			(at 0 0 270)
			(layer "F.Fab")
			(hide yes)
			(effects
				(font
					(size 1.27 1.27)
					(thickness 0.15)
				)
			)
		)
		(property "MPN" "CL10A226MO7JZNC"
			(at 0 0 270)
			(unlocked yes)
			(layer "F.Fab")
			(hide yes)
			(effects
				(font
					(size 1 1)
					(thickness 0.15)
				)
			)
		)
		(property "Manufacturer" "Samsung Electro-Mechanics"
			(at 0 0 270)
			(unlocked yes)
			(layer "F.Fab")
			(hide yes)
			(effects
				(font
					(size 1 1)
					(thickness 0.15)
				)
			)
		)
		(property "License" "Apache-2.0"
			(at 0 0 270)
			(unlocked yes)
			(layer "F.Fab")
			(hide yes)
			(effects
				(font
					(size 1 1)
					(thickness 0.15)
				)
			)
		)
		(property "Author" "Antmicro"
			(at 0 0 270)
			(unlocked yes)
			(layer "F.Fab")
			(hide yes)
			(effects
				(font
					(size 1 1)
					(thickness 0.15)
				)
			)
		)
		(property "Val" "22u"
			(at 0 0 270)
			(unlocked yes)
			(layer "F.Fab")
			(hide yes)
			(effects
				(font
					(size 1 1)
					(thickness 0.15)
				)
			)
		)
		(property "Voltage" "16V"
			(at 0 0 270)
			(unlocked yes)
			(layer "F.Fab")
			(hide yes)
			(effects
				(font
					(size 1 1)
					(thickness 0.15)
				)
			)
		)
		(property "Dielectric" ""
			(at 0 0 270)
			(unlocked yes)
			(layer "F.Fab")
			(hide yes)
			(effects
				(font
					(size 1 1)
					(thickness 0.15)
				)
			)
		)
		(sheetname "/X710-AT2 power/")
		(sheetfile "x710-at2-power.kicad_sch")
		(attr smd)
		(fp_line
			(start -0.15 0.55)
			(end 0.15 0.55)
			(stroke
				(width 0.15)
				(type solid)
			)
			(layer "F.SilkS")
		)
		(fp_line
			(start -0.15 -0.55)
			(end 0.15 -0.55)
			(stroke
				(width 0.15)
				(type solid)
			)
			(layer "F.SilkS")
		)
		(fp_rect
			(start -1.25 -0.65)
			(end 1.25 0.65)
			(stroke
				(width 0.05)
				(type solid)
			)
			(fill no)
			(layer "F.CrtYd")
		)
		(fp_rect
			(start -0.8 -0.45)
			(end 0.8 0.45)
			(stroke
				(width 0.15)
				(type solid)
			)
			(fill no)
			(layer "F.Fab")
		)
		(fp_text user "License: Apache-2.0"
			(at -1.682 5.895 270)
			(layer "F.Fab")
			(effects
				(font
					(size 0.7 0.7)
					(thickness 0.15)
				)
				(justify left bottom)
			)
		)
		(fp_text user "${REFERENCE}"
			(at -1.682 3.895 270)
			(layer "F.Fab")
			(effects
				(font
					(size 0.7 0.7)
					(thickness 0.15)
				)
				(justify left bottom)
			)
		)
		(fp_text user "Author: Antmicro"
			(at -1.682 4.894 270)
			(layer "F.Fab")
			(effects
				(font
					(size 0.7 0.7)
					(thickness 0.15)
				)
				(justify left bottom)
			)
		)
		(pad "1" smd roundrect
			(at -0.7 0 270)
			(size 0.8 1.1)
			(layers "F.Cu" "F.Mask" "F.Paste")
			(roundrect_rratio 0.2)
			(net 23 "GND")
			(pintype "passive")
		)
		(pad "2" smd roundrect
			(at 0.7 0 270)
			(size 0.8 1.1)
			(layers "F.Cu" "F.Mask" "F.Paste")
			(roundrect_rratio 0.2)
			(net 136 "+1V0")
			(pintype "passive")
		)
	)
	(footprint "antmicro-footprints:R_0402_1005Metric"
		(layer "F.Cu")
		(at 140.4 139.55 180)
		(descr "Resistor SMD 0402")
		(tags "resistor SMD 0402")
		(property "Reference" "R16"
			(at 1.2 1.75 180)
			(layer "F.SilkS")
			(effects
				(font
					(size 0.7 0.7)
					(thickness 0.15)
				)
				(justify left bottom)
			)
		)
		(property "Value" "R_0R_0402"
			(at -1.011843 1.772047 180)
			(layer "F.Fab")
			(effects
				(font
					(size 0.7 0.7)
					(thickness 0.15)
				)
				(justify left bottom)
			)
		)
		(property "Datasheet" "https://industrial.panasonic.com/cdbs/www-data/pdf/RDA0000/AOA0000C301.pdf"
			(at 0 0 180)
			(layer "F.Fab")
			(hide yes)
			(effects
				(font
					(size 1.27 1.27)
					(thickness 0.15)
				)
			)
		)
		(property "Description" "SMD Chip Resistor, Jumper, 0 ohm, 100 mW, 0402 [1005 Metric], Thick Film, General Purpose"
			(at 0 0 180)
			(layer "F.Fab")
			(hide yes)
			(effects
				(font
					(size 1.27 1.27)
					(thickness 0.15)
				)
			)
		)
		(property "MPN" "ERJ2GE0R00X"
			(at 0 0 180)
			(unlocked yes)
			(layer "F.Fab")
			(hide yes)
			(effects
				(font
					(size 1 1)
					(thickness 0.15)
				)
			)
		)
		(property "Manufacturer" "Panasonic"
			(at 0 0 180)
			(unlocked yes)
			(layer "F.Fab")
			(hide yes)
			(effects
				(font
					(size 1 1)
					(thickness 0.15)
				)
			)
		)
		(property "License" "Apache-2.0"
			(at 0 0 180)
			(unlocked yes)
			(layer "F.Fab")
			(hide yes)
			(effects
				(font
					(size 1 1)
					(thickness 0.15)
				)
			)
		)
		(property "Val" "0R"
			(at 0 0 180)
			(unlocked yes)
			(layer "F.Fab")
			(hide yes)
			(effects
				(font
					(size 1 1)
					(thickness 0.15)
				)
			)
		)
		(property "Tolerance" "~"
			(at 0 0 180)
			(unlocked yes)
			(layer "F.Fab")
			(hide yes)
			(effects
				(font
					(size 1 1)
					(thickness 0.15)
				)
			)
		)
		(property "Current" "1A"
			(at 0 0 180)
			(unlocked yes)
			(layer "F.Fab")
			(hide yes)
			(effects
				(font
					(size 1 1)
					(thickness 0.15)
				)
			)
		)
		(property "Author" "Antmicro"
			(at 0 0 180)
			(unlocked yes)
			(layer "F.Fab")
			(hide yes)
			(effects
				(font
					(size 1 1)
					(thickness 0.15)
				)
			)
		)
		(sheetname "/PD and TB DC-DC/")
		(sheetfile "PD_and_TB_DC_DC.kicad_sch")
		(attr smd)
		(fp_rect
			(start -0.925 -0.47)
			(end 0.925 0.47)
			(stroke
				(width 0.05)
				(type default)
			)
			(fill no)
			(layer "F.CrtYd")
		)
		(fp_rect
			(start -0.5 -0.25)
			(end 0.5 0.25)
			(stroke
				(width 0.15)
				(type solid)
			)
			(fill no)
			(layer "F.Fab")
		)
		(fp_text user "License: Apache-2.0"
			(at -0.95 5.169 180)
			(layer "F.Fab")
			(effects
				(font
					(size 0.7 0.7)
					(thickness 0.15)
				)
				(justify left bottom)
			)
		)
		(fp_text user "${REFERENCE}"
			(at -0.95 3.168 180)
			(layer "F.Fab")
			(effects
				(font
					(size 0.7 0.7)
					(thickness 0.15)
				)
				(justify left bottom)
			)
		)
		(fp_text user "Author: Antmicro"
			(at -0.95 4.169 180)
			(layer "F.Fab")
			(effects
				(font
					(size 0.7 0.7)
					(thickness 0.15)
				)
				(justify left bottom)
			)
		)
		(pad "1" smd roundrect
			(at -0.48 0 180)
			(size 0.59 0.64)
			(layers "F.Cu" "F.Mask" "F.Paste")
			(roundrect_rratio 0.25)
			(net 374 "/PD and TB DC-DC/HPD")
			(pintype "passive")
		)
		(pad "2" smd roundrect
			(at 0.48 0 180)
			(size 0.59 0.64)
			(layers "F.Cu" "F.Mask" "F.Paste")
			(roundrect_rratio 0.25)
			(net 202 "Net-(U3-GPIO4(HPD_TXRX))")
			(pintype "passive")
		)
	)
	(footprint "antmicro-footprints:C_0402_1005Metric"
		(layer "F.Cu")
		(at 117.8 118 180)
		(descr "Capacitor SMD 0402")
		(tags "capacitor SMD 0402")
		(property "Reference" "C44"
			(at -0.8 -0.2 180)
			(layer "F.SilkS")
			(effects
				(font
					(size 0.7 0.7)
					(thickness 0.15)
				)
				(justify left bottom)
			)
		)
		(property "Value" "C_220n_0402"
			(at -1.022927 2.155213 180)
			(layer "F.Fab")
			(effects
				(font
					(size 0.7 0.7)
					(thickness 0.15)
				)
				(justify left bottom)
			)
		)
		(property "Datasheet" "https://www.yageo.com/en/Chart/Download/pdf/CC0402KRX5R6BB224"
			(at 0 0 180)
			(layer "F.Fab")
			(hide yes)
			(effects
				(font
					(size 1.27 1.27)
					(thickness 0.15)
				)
			)
		)
		(property "Description" "SMD Multilayer Ceramic Capacitor, 0.22 µF, 10 V, 0402 [1005 Metric], ± 10%, X5R, CC Series"
			(at 0 0 180)
			(layer "F.Fab")
			(hide yes)
			(effects
				(font
					(size 1.27 1.27)
					(thickness 0.15)
				)
			)
		)
		(property "MPN" "CC0402KRX5R6BB224"
			(at 0 0 180)
			(unlocked yes)
			(layer "F.Fab")
			(hide yes)
			(effects
				(font
					(size 1 1)
					(thickness 0.15)
				)
			)
		)
		(property "Manufacturer" "YAGEO"
			(at 0 0 180)
			(unlocked yes)
			(layer "F.Fab")
			(hide yes)
			(effects
				(font
					(size 1 1)
					(thickness 0.15)
				)
			)
		)
		(property "License" "Apache-2.0"
			(at 0 0 180)
			(unlocked yes)
			(layer "F.Fab")
			(hide yes)
			(effects
				(font
					(size 1 1)
					(thickness 0.15)
				)
			)
		)
		(property "Val" "220n"
			(at 0 0 180)
			(unlocked yes)
			(layer "F.Fab")
			(hide yes)
			(effects
				(font
					(size 1 1)
					(thickness 0.15)
				)
			)
		)
		(property "Voltage" ""
			(at 0 0 180)
			(unlocked yes)
			(layer "F.Fab")
			(hide yes)
			(effects
				(font
					(size 1 1)
					(thickness 0.15)
				)
			)
		)
		(property "Dielectric" ""
			(at 0 0 180)
			(unlocked yes)
			(layer "F.Fab")
			(hide yes)
			(effects
				(font
					(size 1 1)
					(thickness 0.15)
				)
			)
		)
		(property "Author" "Antmicro"
			(at 0 0 180)
			(unlocked yes)
			(layer "F.Fab")
			(hide yes)
			(effects
				(font
					(size 1 1)
					(thickness 0.15)
				)
			)
		)
		(sheetname "/TB Controller/")
		(sheetfile "tb.kicad_sch")
		(attr smd)
		(fp_rect
			(start -0.925 -0.47)
			(end 0.925 0.47)
			(stroke
				(width 0.05)
				(type default)
			)
			(fill no)
			(layer "F.CrtYd")
		)
		(fp_line
			(start 0.504 0.248)
			(end -0.494 0.248)
			(stroke
				(width 0.15)
				(type solid)
			)
			(layer "F.Fab")
		)
		(fp_line
			(start 0.504 -0.25)
			(end 0.504 0.248)
			(stroke
				(width 0.15)
				(type solid)
			)
			(layer "F.Fab")
		)
		(fp_line
			(start -0.494 0.248)
			(end -0.494 -0.25)
			(stroke
				(width 0.15)
				(type solid)
			)
			(layer "F.Fab")
		)
		(fp_line
			(start -0.494 -0.25)
			(end 0.504 -0.25)
			(stroke
				(width 0.15)
				(type solid)
			)
			(layer "F.Fab")
		)
		(fp_text user "License: Apache-2.0"
			(at -0.939 5.799 180)
			(layer "F.Fab")
			(effects
				(font
					(size 0.7 0.7)
					(thickness 0.15)
				)
				(justify left bottom)
			)
		)
		(fp_text user "${REFERENCE}"
			(at -0.939 4.599 180)
			(layer "F.Fab")
			(effects
				(font
					(size 0.7 0.7)
					(thickness 0.15)
				)
				(justify left bottom)
			)
		)
		(fp_text user "Author: Antmicro"
			(at -0.939 3.399 180)
			(layer "F.Fab")
			(effects
				(font
					(size 0.7 0.7)
					(thickness 0.15)
				)
				(justify left bottom)
			)
		)
		(pad "1" smd roundrect
			(at -0.48 0 180)
			(size 0.59 0.64)
			(layers "F.Cu" "F.Mask" "F.Paste")
			(roundrect_rratio 0.25)
			(net 323 "/TB Controller/TB_PCIE_TX0_P")
			(pintype "passive")
		)
		(pad "2" smd roundrect
			(at 0.48 0 180)
			(size 0.59 0.64)
			(layers "F.Cu" "F.Mask" "F.Paste")
			(roundrect_rratio 0.25)
			(net 314 "/TB Controller/PCIex4.RX0+")
			(pintype "passive")
		)
	)
)
